# T6G (Grand Teton) — schematic netlist excerpt (pin names and nets, part order shuffled) for the footprints in the layout excerpt that follows; sources: Cadence DE-HDL packaged netlist, KiCad conversion of 04192023_DAF0TMB3IC0_F0TG_MB_C_brd_V02_OCP.brd

J86  PICOPROBE_BXA  DELTA-L 4.0 EMPTY  pkg TRIANG_LAUNCH_3PXB  page 229
  \1_p\  = DELTA_L_85_10INCH_IN4_DN
  \2_n\  = DELTA_L_85_10INCH_IN4_DP
  \3_g\  = DELTA_L_GND_1

(kicad_pcb
	(version 20260206)
	(generator "pcbnew")
	(generator_version "10.0")
	(general
		(thickness 1.6)
		(legacy_teardrops no)
	)
	(paper "A4")
	(title_block
		(title "04192023_DAF0TMB3IC0_F0TG_MB_C_brd_V02_OCP.brd")
		(comment 1 "Grand Teton / footprints 5755-5755 of 8354")
	)
	(layers
		(0 "F.Cu" signal "TOP")
		(4 "In1.Cu" signal "GND")
		(6 "In2.Cu" signal "IN1")
		(8 "In3.Cu" signal "GND1")
		(10 "In4.Cu" signal "IN2")
		(12 "In5.Cu" signal "GND2")
		(14 "In6.Cu" signal "IN3")
		(16 "In7.Cu" signal "GND3")
		(18 "In8.Cu" signal "VCC")
		(20 "In9.Cu" signal "VCC1")
		(22 "In10.Cu" signal "GND4")
		(24 "In11.Cu" signal "IN4")
		(26 "In12.Cu" signal "GND5")
		(28 "In13.Cu" signal "IN5")
		(30 "In14.Cu" signal "GND6")
		(32 "In15.Cu" signal "IN6")
		(34 "In16.Cu" signal "GND7")
		(2 "B.Cu" signal "BOTTOM")
		(9 "F.Adhes" user "F.Adhesive")
		(11 "B.Adhes" user "B.Adhesive")
		(13 "F.Paste" user "Package Geometry/Pastemask Top")
		(15 "B.Paste" user "Package Geometry/Pastemask Bottom")
		(5 "F.SilkS" user "Ref Des/Silkscreen Top")
		(7 "B.SilkS" user "Ref Des/Silkscreen Bottom")
		(1 "F.Mask" user "Board Geometry/Soldermask Top")
		(3 "B.Mask" user "Board Geometry/Soldermask Bottom")
		(17 "Dwgs.User" user "User.Drawings")
		(19 "Cmts.User" user "User.Comments")
		(21 "Eco1.User" user "User.Eco1")
		(23 "Eco2.User" user "User.Eco2")
		(25 "Edge.Cuts" user "Board Geometry/Outline")
		(27 "Margin" user)
		(31 "F.CrtYd" user "Package Geometry/Place Bound Top")
		(29 "B.CrtYd" user "Package Geometry/Place Bound Bottom")
		(35 "F.Fab" user "Ref Des/Assembly Top")
		(33 "B.Fab" user "Ref Des/Assembly Bottom")
	)
	(footprint ""
		(layer "B.Cu")
		(at 300.538388 -2.537206)
		(property "Reference" "J86"
			(at 4.532122 1.115568 270)
			(unlocked yes)
			(layer "B.SilkS")
			(effects
				(font
					(size 0.7874 0.5842)
					(thickness 0.1524)
				)
				(justify left mirror)
			)
		)
		(property "Value" ""
			(at 0 0 0)
			(layer "B.Fab")
			(effects
				(font
					(size 1.27 1.27)
				)
				(justify mirror)
			)
		)
		(duplicate_pad_numbers_are_jumpers no)
		(fp_line
			(start -1.2192 -2.06756)
			(end -1.2192 2.06756)
			(stroke
				(width 0.1524)
				(type default)
			)
			(layer "B.SilkS")
		)
		(fp_line
			(start -1.2192 2.06756)
			(end 1.2192 2.06756)
			(stroke
				(width 0.1524)
				(type default)
			)
			(layer "B.SilkS")
		)
		(fp_line
			(start 1.2192 -2.06756)
			(end -1.2192 -2.06756)
			(stroke
				(width 0.1524)
				(type default)
			)
			(layer "B.SilkS")
		)
		(fp_line
			(start 1.2192 2.06756)
			(end 1.2192 -2.06756)
			(stroke
				(width 0.1524)
				(type default)
			)
			(layer "B.SilkS")
		)
		(pad "" np_thru_hole circle
			(at -3.4671 -1.27 270)
			(size 1.0414 1.0414)
			(drill 1.0414)
			(layers "*.Cu" "*.Mask")
			(clearance 0.381)
			(thermal_gap 0.381)
		)
		(pad "" np_thru_hole circle
			(at -3.4671 1.27 270)
			(size 1.0414 1.0414)
			(drill 1.0414)
			(layers "*.Cu" "*.Mask")
			(clearance 0.381)
			(thermal_gap 0.381)
		)
		(pad "" np_thru_hole circle
			(at 2.8829 -1.27 270)
			(size 1.0414 1.0414)
			(drill 1.0414)
			(layers "*.Cu" "*.Mask")
			(clearance 0.381)
			(thermal_gap 0.381)
		)
		(pad "" np_thru_hole circle
			(at 2.8829 1.27 270)
			(size 1.0414 1.0414)
			(drill 1.0414)
			(layers "*.Cu" "*.Mask")
			(clearance 0.381)
			(thermal_gap 0.381)
		)
		(pad "1" smd rect
			(at -0.8255 -0.249936 270)
			(size 0.3048 0.508)
			(layers "B.Cu" "B.Mask" "B.Paste")
			(net "DELTA_L_85_10INCH_IN4_DN")
		)
		(pad "2" smd rect
			(at -0.8255 0.249936 270)
			(size 0.3048 0.508)
			(layers "B.Cu" "B.Mask" "B.Paste")
			(net "DELTA_L_85_10INCH_IN4_DP")
		)
		(pad "3" smd circle
			(at 0 0 180)
			(size 0 0)
			(layers "B.Cu" "B.Mask" "B.Paste")
			(net "DELTA_L_GND_1")
		)
		(zone
			(layers "F.Cu" "B.Cu" "In1.Cu" "In2.Cu" "In3.Cu" "In4.Cu" "In5.Cu" "In6.Cu"
				"In7.Cu" "In8.Cu" "In9.Cu" "In10.Cu" "In11.Cu" "In12.Cu" "In13.Cu" "In14.Cu"
				"In15.Cu" "In16.Cu"
			)
			(hatch none 0.5)
			(connect_pads
				(clearance 0)
			)
			(min_thickness 0.25)
			(keepout
				(tracks not_allowed)
				(vias allowed)
				(pads allowed)
				(copperpour not_allowed)
				(footprints allowed)
			)
			(placement
				(enabled no)
				(sheetname "")
			)
			(fill
				(thermal_gap 0.5)
				(thermal_bridge_width 0.5)
				(island_removal_mode 0)
			)
			(polygon
				(pts
					(arc
						(start 297.998388 -3.807206)
						(mid 296.144188 -3.807206)
						(end 297.998388 -3.807206)
					)
				)
			)
		)
		(zone
			(layers "F.Cu" "B.Cu" "In1.Cu" "In2.Cu" "In3.Cu" "In4.Cu" "In5.Cu" "In6.Cu"
				"In7.Cu" "In8.Cu" "In9.Cu" "In10.Cu" "In11.Cu" "In12.Cu" "In13.Cu" "In14.Cu"
				"In15.Cu" "In16.Cu"
			)
			(hatch none 0.5)
			(connect_pads
				(clearance 0)
			)
			(min_thickness 0.25)
			(keepout
				(tracks not_allowed)
				(vias allowed)
				(pads allowed)
				(copperpour not_allowed)
				(footprints allowed)
			)
			(placement
				(enabled no)
				(sheetname "")
			)
			(fill
				(thermal_gap 0.5)
				(thermal_bridge_width 0.5)
				(island_removal_mode 0)
			)
			(polygon
				(pts
					(arc
						(start 297.998388 -1.267206)
						(mid 296.144188 -1.267206)
						(end 297.998388 -1.267206)
					)
				)
			)
		)
		(zone
			(layers "F.Cu" "B.Cu" "In1.Cu" "In2.Cu" "In3.Cu" "In4.Cu" "In5.Cu" "In6.Cu"
				"In7.Cu" "In8.Cu" "In9.Cu" "In10.Cu" "In11.Cu" "In12.Cu" "In13.Cu" "In14.Cu"
				"In15.Cu" "In16.Cu"
			)
			(hatch none 0.5)
			(connect_pads
				(clearance 0)
			)
			(min_thickness 0.25)
			(keepout
				(tracks not_allowed)
				(vias allowed)
				(pads allowed)
				(copperpour not_allowed)
				(footprints allowed)
			)
			(placement
				(enabled no)
				(sheetname "")
			)
			(fill
				(thermal_gap 0.5)
				(thermal_bridge_width 0.5)
				(island_removal_mode 0)
			)
			(polygon
				(pts
					(arc
						(start 304.348388 -3.807206)
						(mid 302.494188 -3.807206)
						(end 304.348388 -3.807206)
					)
				)
			)
		)
		(zone
			(layers "F.Cu" "B.Cu" "In1.Cu" "In2.Cu" "In3.Cu" "In4.Cu" "In5.Cu" "In6.Cu"
				"In7.Cu" "In8.Cu" "In9.Cu" "In10.Cu" "In11.Cu" "In12.Cu" "In13.Cu" "In14.Cu"
				"In15.Cu" "In16.Cu"
			)
			(hatch none 0.5)
			(connect_pads
				(clearance 0)
			)
			(min_thickness 0.25)
			(keepout
				(tracks not_allowed)
				(vias allowed)
				(pads allowed)
				(copperpour not_allowed)
				(footprints allowed)
			)
			(placement
				(enabled no)
				(sheetname "")
			)
			(fill
				(thermal_gap 0.5)
				(thermal_bridge_width 0.5)
				(island_removal_mode 0)
			)
			(polygon
				(pts
					(arc
						(start 304.348388 -1.267206)
						(mid 302.494188 -1.267206)
						(end 304.348388 -1.267206)
					)
				)
			)
		)
		(zone
			(layer "B.Cu")
			(hatch none 0.5)
			(connect_pads
				(clearance 0)
			)
			(min_thickness 0.25)
			(keepout
				(tracks not_allowed)
				(vias allowed)
				(pads allowed)
				(copperpour not_allowed)
				(footprints allowed)
			)
			(placement
				(enabled no)
				(sheetname "")
			)
			(fill
				(thermal_gap 0.5)
				(thermal_bridge_width 0.5)
				(island_removal_mode 0)
			)
			(polygon
				(pts
					(xy 299.420788 -3.085846) (xy 299.420788 -2.990342) (xy 300.017688 -2.990342) (xy 300.017688 -2.583942)
					(xy 299.420788 -2.583942) (xy 299.420788 -2.49047) (xy 300.017688 -2.49047) (xy 300.017688 -2.08407)
					(xy 299.420788 -2.08407) (xy 299.420788 -1.988566) (xy 300.119288 -1.988566) (xy 300.119288 -3.085846)
				)
			)
		)
	)
)
